# S9S_MB_2U (Grand Teton) — schematic netlist excerpt (pin names and nets, part order shuffled) for the footprints in the layout excerpt that follows; sources: Cadence DE-HDL packaged netlist, KiCad conversion of 03242023_DA0F0TMBIJ0_F0T_Motherboard_J_brd_V01_OCP.brd

U61  NC7SB3157  NC7SB3157P6X IC  pkg SMLF  page 202
  B1  = RST_ESPI_RESET_N_R
  GND  = GND
  B0  = RST_PLTRST_B_MUX_N
  A  = ESPI_BMC_LPC_RST_N
  VCC  = PGPPA_AUX
  S  = FM_ESPI_PLD_EN

R3236  Q_RES  0 5% CHIP  pkg 0402LF  page 161 : A = RST_HP_OCP_V3_2_R_N ; B = RST_SMB_OCP_V3_2_N

(kicad_pcb
	(version 20260206)
	(generator "pcbnew")
	(generator_version "10.0")
	(general
		(thickness 1.6)
		(legacy_teardrops no)
	)
	(paper "A4")
	(title_block
		(title "03242023_DA0F0TMBIJ0_F0T_Motherboard_J_brd_V01_OCP.brd")
		(comment 1 "Grand Teton / footprints 1798-1799 of 6105")
	)
	(layers
		(0 "F.Cu" signal "TOP")
		(4 "In1.Cu" signal "GND")
		(6 "In2.Cu" signal "IN1")
		(8 "In3.Cu" signal "GND1")
		(10 "In4.Cu" signal "IN2")
		(12 "In5.Cu" signal "GND2")
		(14 "In6.Cu" signal "IN3")
		(16 "In7.Cu" signal "GND3")
		(18 "In8.Cu" signal "VCC")
		(20 "In9.Cu" signal "VCC1")
		(22 "In10.Cu" signal "GND4")
		(24 "In11.Cu" signal "IN4")
		(26 "In12.Cu" signal "GND5")
		(28 "In13.Cu" signal "IN5")
		(30 "In14.Cu" signal "GND6")
		(32 "In15.Cu" signal "IN6")
		(34 "In16.Cu" signal "GND7")
		(2 "B.Cu" signal "BOTTOM")
		(9 "F.Adhes" user "F.Adhesive")
		(11 "B.Adhes" user "B.Adhesive")
		(13 "F.Paste" user "Package Geometry/Pastemask Top")
		(15 "B.Paste" user "Package Geometry/Pastemask Bottom")
		(5 "F.SilkS" user "Ref Des/Silkscreen Top")
		(7 "B.SilkS" user "Ref Des/Silkscreen Bottom")
		(1 "F.Mask" user "Board Geometry/Soldermask Top")
		(3 "B.Mask" user "Board Geometry/Soldermask Bottom")
		(17 "Dwgs.User" user "User.Drawings")
		(19 "Cmts.User" user "User.Comments")
		(21 "Eco1.User" user "User.Eco1")
		(23 "Eco2.User" user "User.Eco2")
		(25 "Edge.Cuts" user "Board Geometry/Outline")
		(27 "Margin" user)
		(31 "F.CrtYd" user "Package Geometry/Place Bound Top")
		(29 "B.CrtYd" user "Package Geometry/Place Bound Bottom")
		(35 "F.Fab" user "Ref Des/Assembly Top")
		(33 "B.Fab" user "Ref Des/Assembly Bottom")
	)
	(footprint ""
		(layer "F.Cu")
		(at 153.21788 -114.137948 180)
		(property "Reference" "R3236"
			(at 0 0 180)
			(layer "F.SilkS")
			(hide yes)
			(effects
				(font
					(size 1.27 1.27)
				)
			)
		)
		(property "Value" ""
			(at 0 0 180)
			(layer "F.Fab")
			(effects
				(font
					(size 1.27 1.27)
				)
			)
		)
		(duplicate_pad_numbers_are_jumpers no)
		(fp_line
			(start 0.7874 0.4064)
			(end -0.7874 0.4064)
			(stroke
				(width 0.1524)
				(type default)
			)
			(layer "F.SilkS")
		)
		(fp_line
			(start 0.7874 -0.4064)
			(end 0.7874 0.4064)
			(stroke
				(width 0.1524)
				(type default)
			)
			(layer "F.SilkS")
		)
		(fp_line
			(start -0.7874 0.4064)
			(end -0.7874 -0.4064)
			(stroke
				(width 0.1524)
				(type default)
			)
			(layer "F.SilkS")
		)
		(fp_line
			(start -0.7874 -0.4064)
			(end 0.7874 -0.4064)
			(stroke
				(width 0.1524)
				(type default)
			)
			(layer "F.SilkS")
		)
		(fp_line
			(start 0.67945 0.3048)
			(end 0.120396 0.3048)
			(stroke
				(width 0.1)
				(type default)
			)
			(layer "F.Fab")
		)
		(fp_line
			(start 0.67945 -0.3048)
			(end 0.67945 0.3048)
			(stroke
				(width 0.1)
				(type default)
			)
			(layer "F.Fab")
		)
		(fp_line
			(start 0.12065 -0.2794)
			(end 0.12065 -0.3048)
			(stroke
				(width 0.1)
				(type default)
			)
			(layer "F.Fab")
		)
		(fp_line
			(start 0.12065 -0.3048)
			(end 0.67945 -0.3048)
			(stroke
				(width 0.1)
				(type default)
			)
			(layer "F.Fab")
		)
		(fp_line
			(start 0.120396 0.3048)
			(end 0.120396 0.2794)
			(stroke
				(width 0.1)
				(type default)
			)
			(layer "F.Fab")
		)
		(fp_line
			(start 0.120396 0.2794)
			(end -0.12065 0.2794)
			(stroke
				(width 0.1)
				(type default)
			)
			(layer "F.Fab")
		)
		(fp_line
			(start -0.12065 0.3048)
			(end -0.67945 0.3048)
			(stroke
				(width 0.1)
				(type default)
			)
			(layer "F.Fab")
		)
		(fp_line
			(start -0.12065 0.2794)
			(end -0.12065 0.3048)
			(stroke
				(width 0.1)
				(type default)
			)
			(layer "F.Fab")
		)
		(fp_line
			(start -0.12065 -0.2794)
			(end 0.12065 -0.2794)
			(stroke
				(width 0.1)
				(type default)
			)
			(layer "F.Fab")
		)
		(fp_line
			(start -0.12065 -0.305054)
			(end -0.12065 -0.2794)
			(stroke
				(width 0.1)
				(type default)
			)
			(layer "F.Fab")
		)
		(fp_line
			(start -0.67945 0.3048)
			(end -0.67945 -0.305054)
			(stroke
				(width 0.1)
				(type default)
			)
			(layer "F.Fab")
		)
		(fp_line
			(start -0.67945 -0.305054)
			(end -0.12065 -0.305054)
			(stroke
				(width 0.1)
				(type default)
			)
			(layer "F.Fab")
		)
		(pad "1" smd circle
			(at -0.40005 0 180)
			(size 0 0)
			(layers "F.Cu" "F.Mask" "F.Paste")
			(net "RST_HP_OCP_V3_2_R_N")
		)
		(pad "2" smd circle
			(at 0.40005 0 180)
			(size 0 0)
			(layers "F.Cu" "F.Mask" "F.Paste")
			(net "RST_SMB_OCP_V3_2_N")
		)
	)
	(footprint ""
		(layer "F.Cu")
		(at 334.385412 -21.60778 -90)
		(property "Reference" "U61"
			(at -1.967738 -5.486908 0)
			(unlocked yes)
			(layer "F.SilkS")
			(effects
				(font
					(size 0.7874 0.5842)
					(thickness 0.1524)
				)
			)
		)
		(property "Value" ""
			(at 0 0 270)
			(layer "F.Fab")
			(effects
				(font
					(size 1.27 1.27)
				)
			)
		)
		(duplicate_pad_numbers_are_jumpers no)
		(fp_line
			(start -1.7272 1.1176)
			(end -1.7272 -1.1176)
			(stroke
				(width 0.1524)
				(type default)
			)
			(layer "F.SilkS")
		)
		(fp_line
			(start 1.7272 1.1176)
			(end -1.7272 1.1176)
			(stroke
				(width 0.1524)
				(type default)
			)
			(layer "F.SilkS")
		)
		(fp_line
			(start 0 -0.7366)
			(end -0.254 -1.1176)
			(stroke
				(width 0.1524)
				(type default)
			)
			(layer "F.SilkS")
		)
		(fp_line
			(start -0.254 -1.1176)
			(end -1.7272 -1.1176)
			(stroke
				(width 0.1524)
				(type default)
			)
			(layer "F.SilkS")
		)
		(fp_line
			(start 0.254 -1.1176)
			(end 0 -0.7366)
			(stroke
				(width 0.1524)
				(type default)
			)
			(layer "F.SilkS")
		)
		(fp_line
			(start 1.7272 -1.1176)
			(end 1.7272 1.1176)
			(stroke
				(width 0.1524)
				(type default)
			)
			(layer "F.SilkS")
		)
		(fp_line
			(start 1.7272 -1.1176)
			(end 0.254 -1.1176)
			(stroke
				(width 0.1524)
				(type default)
			)
			(layer "F.SilkS")
		)
		(fp_poly
			(pts
				(xy -2.699766 -0.808736) (xy -2.440686 -1.525524) (xy -1.853692 -0.90805)
			)
			(stroke
				(width 0)
				(type default)
			)
			(fill yes)
			(layer "F.SilkS")
		)
		(fp_line
			(start -1.5748 1.1176)
			(end 1.5748 1.1176)
			(stroke
				(width 0.1)
				(type default)
			)
			(layer "F.Fab")
		)
		(fp_line
			(start 1.5748 1.1176)
			(end 1.5748 -1.1176)
			(stroke
				(width 0.1)
				(type default)
			)
			(layer "F.Fab")
		)
		(fp_line
			(start -1.5748 -1.1176)
			(end -1.5748 1.1176)
			(stroke
				(width 0.1)
				(type default)
			)
			(layer "F.Fab")
		)
		(fp_line
			(start 1.5748 -1.1176)
			(end -1.5748 -1.1176)
			(stroke
				(width 0.1)
				(type default)
			)
			(layer "F.Fab")
		)
		(fp_poly
			(pts
				(xy -1.9558 -0.649986) (xy -2.7178 -0.268986) (xy -2.7178 -1.030986)
			)
			(stroke
				(width 0)
				(type default)
			)
			(fill yes)
			(layer "F.Fab")
		)
		(pad "1" smd rect
			(at -0.999998 -0.649986 180)
			(size 0.3556 1.1176)
			(layers "F.Cu" "F.Mask" "F.Paste")
			(net "RST_ESPI_RESET_N_R")
		)
		(pad "2" smd rect
			(at -0.999998 0 180)
			(size 0.3556 1.1176)
			(layers "F.Cu" "F.Mask" "F.Paste")
			(net "GND")
		)
		(pad "3" smd rect
			(at -0.999998 0.649986 180)
			(size 0.3556 1.1176)
			(layers "F.Cu" "F.Mask" "F.Paste")
			(net "RST_PLTRST_B_MUX_N")
		)
		(pad "4" smd rect
			(at 0.999998 0.649986 180)
			(size 0.3556 1.1176)
			(layers "F.Cu" "F.Mask" "F.Paste")
			(net "ESPI_BMC_LPC_RST_N")
		)
		(pad "5" smd rect
			(at 0.999998 0 180)
			(size 0.3556 1.1176)
			(layers "F.Cu" "F.Mask" "F.Paste")
			(net "PGPPA_AUX")
		)
		(pad "6" smd rect
			(at 0.999998 -0.649986 180)
			(size 0.3556 1.1176)
			(layers "F.Cu" "F.Mask" "F.Paste")
			(net "FM_ESPI_PLD_EN")
		)
	)
)
